(kicad_pcb
	(version 20241229)
	(generator "pcbnew")
	(generator_version "9.0")
	(general
		(thickness 1.294)
		(legacy_teardrops no)
	)
	(paper "A3")
	(title_block
		(title "Kintex 410T devboard")
		(date "2024-04-03")
		(rev "1.1.2")
		(comment 9 "footprints 197-199 of 975")
	)
	(layers
		(0 "F.Cu" mixed)
		(4 "In1.Cu" power)
		(6 "In2.Cu" power)
		(8 "In3.Cu" mixed)
		(10 "In4.Cu" power)
		(12 "In5.Cu" mixed)
		(14 "In6.Cu" power)
		(16 "In7.Cu" mixed)
		(18 "In8.Cu" power)
		(2 "B.Cu" mixed)
		(9 "F.Adhes" user "F.Adhesive")
		(11 "B.Adhes" user "B.Adhesive")
		(13 "F.Paste" user)
		(15 "B.Paste" user)
		(5 "F.SilkS" user "F.Silkscreen")
		(7 "B.SilkS" user "B.Silkscreen")
		(1 "F.Mask" user)
		(3 "B.Mask" user)
		(17 "Dwgs.User" user "User.Drawings")
		(19 "Cmts.User" user "User.Comments")
		(21 "Eco1.User" user "User.Eco1")
		(23 "Eco2.User" user "User.Eco2")
		(25 "Edge.Cuts" user)
		(27 "Margin" user)
		(31 "F.CrtYd" user "F.Courtyard")
		(29 "B.CrtYd" user "B.Courtyard")
		(35 "F.Fab" user)
		(33 "B.Fab" user)
	)
	(footprint "antmicro-footprints:R_0402_1005Metric"
		(layer "F.Cu")
		(at 225.025 121.5)
		(descr "Resistor SMD 0402")
		(tags "resistor SMD 0402")
		(property "Reference" "R78"
			(at -2.975 0.4 0)
			(layer "F.SilkS")
			(effects
				(font
					(size 0.7 0.7)
					(thickness 0.15)
				)
				(justify left bottom)
			)
		)
		(property "Value" "R_0R_0402"
			(at 0 1.4 0)
			(layer "F.Fab")
			(effects
				(font
					(size 0.7 0.7)
					(thickness 0.15)
				)
				(justify left bottom)
			)
		)
		(property "Description" "SMD Chip Resistor, Jumper, 0 ohm, 100 mW, 0402 [1005 Metric], Thick Film, General Purpose"
			(at 0 0 0)
			(layer "F.Fab")
			(hide yes)
			(effects
				(font
					(size 1.27 1.27)
					(thickness 0.15)
				)
			)
		)
		(property "Author" "Antmicro"
			(at 0 0 0)
			(layer "F.Fab")
			(hide yes)
			(effects
				(font
					(size 1 1)
					(thickness 0.15)
				)
			)
		)
		(property "Current" "1A"
			(at 0 0 0)
			(layer "F.Fab")
			(hide yes)
			(effects
				(font
					(size 1 1)
					(thickness 0.15)
				)
			)
		)
		(property "License" "Apache-2.0"
			(at 0 0 0)
			(layer "F.Fab")
			(hide yes)
			(effects
				(font
					(size 1 1)
					(thickness 0.15)
				)
			)
		)
		(property "MPN" "ERJ2GE0R00X"
			(at 0 0 0)
			(layer "F.Fab")
			(hide yes)
			(effects
				(font
					(size 1 1)
					(thickness 0.15)
				)
			)
		)
		(property "Manufacturer" "Panasonic"
			(at 0 0 0)
			(layer "F.Fab")
			(hide yes)
			(effects
				(font
					(size 1 1)
					(thickness 0.15)
				)
			)
		)
		(property "Tolerance" ""
			(at 0 0 0)
			(layer "F.Fab")
			(hide yes)
			(effects
				(font
					(size 1 1)
					(thickness 0.15)
				)
			)
		)
		(property "Val" "0R"
			(at 0 0 0)
			(layer "F.Fab")
			(hide yes)
			(effects
				(font
					(size 1 1)
					(thickness 0.15)
				)
			)
		)
		(sheetname "SPI Flash + SD Card")
		(sheetfile "spi-flash.kicad_sch")
		(attr smd)
		(fp_rect
			(start -0.925 -0.47)
			(end 0.925 0.47)
			(stroke
				(width 0.05)
				(type default)
			)
			(fill no)
			(layer "F.CrtYd")
		)
		(fp_rect
			(start -0.5 -0.25)
			(end 0.5 0.25)
			(stroke
				(width 0.15)
				(type solid)
			)
			(fill no)
			(layer "F.Fab")
		)
		(pad "1" smd roundrect
			(at -0.48 0)
			(size 0.59 0.64)
			(layers "F.Cu" "F.Mask" "F.Paste")
			(roundrect_rratio 0.25)
			(net 403 "/FPGA Bank 14 & 15/SYSTEM_FLASH.DQ2")
			(pintype "passive")
		)
		(pad "2" smd roundrect
			(at 0.48 0)
			(size 0.59 0.64)
			(layers "F.Cu" "F.Mask" "F.Paste")
			(roundrect_rratio 0.25)
			(net 898 "/SPI Flash + SD Card/SYSTEM_FLASH_DQ2")
			(pintype "passive")
		)
	)
	(footprint "antmicro-footprints:R_0402_1005Metric"
		(layer "F.Cu")
		(at 235.915 119.5 180)
		(descr "Resistor SMD 0402")
		(tags "resistor SMD 0402")
		(property "Reference" "R70"
			(at -0.735 -0.35 180)
			(layer "F.SilkS")
			(effects
				(font
					(size 0.7 0.7)
					(thickness 0.15)
				)
				(justify left bottom)
			)
		)
		(property "Value" "R_100R_0402"
			(at 0 1.4 180)
			(layer "F.Fab")
			(effects
				(font
					(size 0.7 0.7)
					(thickness 0.15)
				)
				(justify left bottom)
			)
		)
		(property "Description" "SMD Chip Resistor, 100 ohm, ± 1%, 62.5 mW, 0402 [1005 Metric], Thick Film, General Purpose"
			(at 0 0 180)
			(layer "F.Fab")
			(hide yes)
			(effects
				(font
					(size 1.27 1.27)
					(thickness 0.15)
				)
			)
		)
		(property "Author" "Antmicro"
			(at 471.83 239 0)
			(layer "F.Fab")
			(hide yes)
			(effects
				(font
					(size 1 1)
					(thickness 0.15)
				)
			)
		)
		(property "DNP" "DNP"
			(at 471.83 239 0)
			(layer "F.Fab")
			(hide yes)
			(effects
				(font
					(size 1 1)
					(thickness 0.15)
				)
			)
		)
		(property "License" "Apache-2.0"
			(at 471.83 239 0)
			(layer "F.Fab")
			(hide yes)
			(effects
				(font
					(size 1 1)
					(thickness 0.15)
				)
			)
		)
		(property "MPN" "CR0402-FX-1000GLF"
			(at 471.83 239 0)
			(layer "F.Fab")
			(hide yes)
			(effects
				(font
					(size 1 1)
					(thickness 0.15)
				)
			)
		)
		(property "Manufacturer" "Bourns"
			(at 471.83 239 0)
			(layer "F.Fab")
			(hide yes)
			(effects
				(font
					(size 1 1)
					(thickness 0.15)
				)
			)
		)
		(property "Tolerance" "1%"
			(at 471.83 239 0)
			(layer "F.Fab")
			(hide yes)
			(effects
				(font
					(size 1 1)
					(thickness 0.15)
				)
			)
		)
		(property "Val" "100R"
			(at 471.83 239 0)
			(layer "F.Fab")
			(hide yes)
			(effects
				(font
					(size 1 1)
					(thickness 0.15)
				)
			)
		)
		(property "dnp" ""
			(at 471.83 239 0)
			(layer "F.Fab")
			(hide yes)
			(effects
				(font
					(size 1 1)
					(thickness 0.15)
				)
			)
		)
		(property "exclude_from_bom" ""
			(at 471.83 239 0)
			(layer "F.Fab")
			(hide yes)
			(effects
				(font
					(size 1 1)
					(thickness 0.15)
				)
			)
		)
		(sheetname "SPI Flash + SD Card")
		(sheetfile "spi-flash.kicad_sch")
		(attr smd exclude_from_bom)
		(fp_rect
			(start -0.925 -0.47)
			(end 0.925 0.47)
			(stroke
				(width 0.05)
				(type default)
			)
			(fill no)
			(layer "F.CrtYd")
		)
		(fp_rect
			(start -0.5 -0.25)
			(end 0.5 0.25)
			(stroke
				(width 0.15)
				(type solid)
			)
			(fill no)
			(layer "F.Fab")
		)
		(pad "1" smd roundrect
			(at -0.48 0 180)
			(size 0.59 0.64)
			(layers "F.Cu" "F.Mask" "F.Paste")
			(roundrect_rratio 0.25)
			(net 56 "/FPGA Bank 14 & 15/SYSTEM_FLASH.CLK")
			(pintype "passive")
		)
		(pad "2" smd roundrect
			(at 0.48 0 180)
			(size 0.59 0.64)
			(layers "F.Cu" "F.Mask" "F.Paste")
			(roundrect_rratio 0.25)
			(net 24 "+3V3")
			(pintype "passive")
		)
	)
	(footprint "antmicro-footprints:MP_Pad6mm_Drill3mm"
		(locked yes)
		(layer "F.Cu")
		(at 266.5 186.5)
		(property "Reference" "MH2"
			(at -0.178 4.025 0)
			(layer "F.SilkS")
			(hide yes)
			(effects
				(font
					(size 0.7 0.7)
					(thickness 0.15)
				)
				(justify left bottom)
			)
		)
		(property "Value" "MP_Pad6mm_Drill3mm"
			(at -0.153 -4.153 0)
			(layer "F.Fab")
			(effects
				(font
					(size 0.7 0.7)
					(thickness 0.15)
				)
				(justify left bottom)
			)
		)
		(property "Description" "Mechanical part"
			(at 0 0 0)
			(layer "F.Fab")
			(hide yes)
			(effects
				(font
					(size 1.27 1.27)
					(thickness 0.15)
				)
			)
		)
		(property "Author" "Antmicro"
			(at 0 0 0)
			(layer "F.Fab")
			(hide yes)
			(effects
				(font
					(size 1 1)
					(thickness 0.15)
				)
			)
		)
		(property "License" "Apache-2.0"
			(at 0 0 0)
			(layer "F.Fab")
			(hide yes)
			(effects
				(font
					(size 1 1)
					(thickness 0.15)
				)
			)
		)
		(property "MPN" ""
			(at 0 0 0)
			(layer "F.Fab")
			(hide yes)
			(effects
				(font
					(size 1 1)
					(thickness 0.15)
				)
			)
		)
		(property "Manufacturer" ""
			(at 0 0 0)
			(layer "F.Fab")
			(hide yes)
			(effects
				(font
					(size 1 1)
					(thickness 0.15)
				)
			)
		)
		(property "exclude_from_bom" ""
			(at 0 0 0)
			(layer "F.Fab")
			(hide yes)
			(effects
				(font
					(size 1 1)
					(thickness 0.15)
				)
			)
		)
		(sheetfile "k410t-devboard.kicad_sch")
		(attr exclude_from_pos_files exclude_from_bom)
		(pad "1" thru_hole circle
			(at 0 0)
			(size 6 6)
			(drill 3)
			(layers "*.Cu" "*.Mask")
			(remove_unused_layers no)
			(net 1 "GND")
			(pintype "passive")
		)
	)
)
